(kicad_pcb
	(version 20260206)
	(generator "pcbnew")
	(generator_version "10.0")
	(general
		(thickness 1.6)
		(legacy_teardrops no)
	)
	(paper "A4")
	(title_block
		(title "Bryce Canyon_F.DPB_16315-1-OCP.brd")
		(comment 1 "Bryce Canyon / footprints 1606-1608 of 2223")
	)
	(layers
		(0 "F.Cu" signal "TOP")
		(4 "In1.Cu" signal "L2GND")
		(6 "In2.Cu" signal "L3")
		(8 "In3.Cu" signal "L4GND")
		(10 "In4.Cu" signal "L5")
		(12 "In5.Cu" signal "L6VCC")
		(14 "In6.Cu" signal "L7VCC")
		(16 "In7.Cu" signal "L8")
		(18 "In8.Cu" signal "L9GND")
		(20 "In9.Cu" signal "L10")
		(22 "In10.Cu" signal "L11GND")
		(2 "B.Cu" signal "BOTTOM")
		(9 "F.Adhes" user "F.Adhesive")
		(11 "B.Adhes" user "B.Adhesive")
		(13 "F.Paste" user "Package Geometry/Pastemask Top")
		(15 "B.Paste" user "Package Geometry/Pastemask Bottom")
		(5 "F.SilkS" user "Ref Des/Silkscreen Top")
		(7 "B.SilkS" user "Ref Des/Silkscreen Bottom")
		(1 "F.Mask" user "Board Geometry/Soldermask Top")
		(3 "B.Mask" user "Board Geometry/Soldermask Bottom")
		(17 "Dwgs.User" user "User.Drawings")
		(19 "Cmts.User" user "User.Comments")
		(21 "Eco1.User" user "User.Eco1")
		(23 "Eco2.User" user "User.Eco2")
		(25 "Edge.Cuts" user "Board Geometry/Outline")
		(27 "Margin" user)
		(31 "F.CrtYd" user "Package Geometry/Place Bound Top")
		(29 "B.CrtYd" user "Package Geometry/Place Bound Bottom")
		(35 "F.Fab" user "Ref Des/Assembly Top")
		(33 "B.Fab" user "Ref Des/Assembly Bottom")
	)
	(footprint ""
		(layer "F.Cu")
		(at 122.849894 -287.910016 -90)
		(property "Reference" "HDDSAS3"
			(at 0 0 270)
			(layer "F.SilkS")
			(hide yes)
			(effects
				(font
					(size 1.27 1.27)
				)
			)
		)
		(property "Value" "SKT-SAS15P-14P-45-GP"
			(at -20.7645 -8.9789 270)
			(unlocked yes)
			(layer "F.Fab")
			(hide yes)
			(effects
				(font
					(size 1.016 1.016)
					(thickness 0.1524)
				)
			)
		)
		(property "Device Type" "10120818-001C-TRLF"
			(at -20.7645 -10.5029 270)
			(unlocked yes)
			(layer "F.Fab")
			(hide yes)
			(effects
				(font
					(size 1.016 1.016)
					(thickness 0.1524)
				)
			)
		)
		(duplicate_pad_numbers_are_jumpers no)
		(fp_line
			(start 1.651 4.2926)
			(end 1.651 3.0099)
			(stroke
				(width 0.1524)
				(type default)
			)
			(layer "F.SilkS")
		)
		(fp_line
			(start 8.509 4.2926)
			(end 1.651 4.2926)
			(stroke
				(width 0.1524)
				(type default)
			)
			(layer "F.SilkS")
		)
		(fp_line
			(start -23.4188 3.0099)
			(end -23.4188 -3.2512)
			(stroke
				(width 0.1524)
				(type default)
			)
			(layer "F.SilkS")
		)
		(fp_line
			(start 1.651 3.0099)
			(end -23.4188 3.0099)
			(stroke
				(width 0.1524)
				(type default)
			)
			(layer "F.SilkS")
		)
		(fp_line
			(start 8.509 3.0099)
			(end 8.509 4.2926)
			(stroke
				(width 0.1524)
				(type default)
			)
			(layer "F.SilkS")
		)
		(fp_line
			(start 23.4188 3.0099)
			(end 8.509 3.0099)
			(stroke
				(width 0.1524)
				(type default)
			)
			(layer "F.SilkS")
		)
		(fp_line
			(start -23.4188 -3.2512)
			(end 23.4188 -3.2512)
			(stroke
				(width 0.1524)
				(type default)
			)
			(layer "F.SilkS")
		)
		(fp_line
			(start 23.4188 -3.2512)
			(end 23.4188 3.0099)
			(stroke
				(width 0.1524)
				(type default)
			)
			(layer "F.SilkS")
		)
		(fp_line
			(start 15.5067 -3.3401)
			(end 16.2687 -3.3401)
			(stroke
				(width 0.3302)
				(type default)
			)
			(layer "F.SilkS")
		)
		(fp_poly
			(pts
				(xy 15.868904 -3.230372) (xy 16.503904 -3.865372) (xy 15.233904 -3.865372)
			)
			(stroke
				(width 0)
				(type default)
			)
			(fill yes)
			(layer "F.SilkS")
		)
		(fp_poly
			(pts
				(xy -22.8727 -2.7559) (xy 22.8727 -2.7559) (xy 22.8727 2.7559) (xy 8.255 2.7559) (xy 8.255 3.5179)
				(xy 1.905 3.5179) (xy 1.905 2.7559) (xy -22.8727 2.7559)
			)
			(stroke
				(width 0)
				(type default)
			)
			(fill no)
			(layer "F.CrtYd")
		)
		(fp_poly
			(pts
				(xy 1.397 4.5466) (xy 1.397 3.2639) (xy -23.6728 3.2639) (xy -23.6728 -3.5052) (xy 23.6728 -3.5052)
				(xy 23.6728 -0.00635) (xy 22.8727 -0.00635) (xy 22.8727 -2.7559) (xy -22.8727 -2.7559) (xy -22.8727 2.7559)
				(xy 1.905 2.7559) (xy 1.905 3.5179) (xy 8.255 3.5179) (xy 8.255 2.7559) (xy 22.8727 2.7559) (xy 22.8727 0.00635)
				(xy 23.6728 0.00635) (xy 23.6728 3.2639) (xy 8.763 3.2639) (xy 8.763 4.5466)
			)
			(stroke
				(width 0)
				(type default)
			)
			(fill no)
			(layer "F.CrtYd")
		)
		(fp_poly
			(pts
				(xy 1.397 4.5466) (xy 1.397 3.2639) (xy -23.6728 3.2639) (xy -23.6728 -3.5052) (xy 23.6728 -3.5052)
				(xy 23.6728 3.2639) (xy 8.763 3.2639) (xy 8.763 4.5466)
			)
			(stroke
				(width 0)
				(type default)
			)
			(fill no)
			(layer "F.Fab")
		)
		(pad "" np_thru_hole circle
			(at -18.874994 0 270)
			(size 0.254 0.254)
			(drill 1.3462)
			(layers "*.Cu" "*.Mask")
			(clearance 0.9017)
			(thermal_gap 0.9017)
		)
		(pad "" np_thru_hole circle
			(at 18.874994 0 270)
			(size 0.254 0.254)
			(drill 0.9398)
			(layers "*.Cu" "*.Mask")
			(clearance 0.6985)
			(thermal_gap 0.6985)
		)
		(pad "G1" smd rect
			(at 21.874988 0 270)
			(size 2.5908 2.5908)
			(layers "F.Cu" "F.Mask" "F.Paste")
			(net "GND")
		)
		(pad "G2" smd rect
			(at -21.874988 0 270)
			(size 2.5908 2.5908)
			(layers "F.Cu" "F.Mask" "F.Paste")
			(net "GND")
		)
		(pad "P1" smd rect
			(at 1.905 -1.82499 270)
			(size 0.6096 2.3622)
			(layers "F.Cu" "F.Mask" "F.Paste")
			(net "Net_2026")
		)
		(pad "P2" smd rect
			(at 0.635 -1.82499 270)
			(size 0.6096 2.3622)
			(layers "F.Cu" "F.Mask" "F.Paste")
			(net "Net_2027")
		)
		(pad "P3" smd rect
			(at -0.635 -1.82499 270)
			(size 0.6096 2.3622)
			(layers "F.Cu" "F.Mask" "F.Paste")
			(net "Net_2028")
		)
		(pad "P4" smd rect
			(at -1.905 -1.82499 270)
			(size 0.6096 2.3622)
			(layers "F.Cu" "F.Mask" "F.Paste")
			(net "GND")
		)
		(pad "P5" smd rect
			(at -3.175 -1.82499 270)
			(size 0.6096 2.3622)
			(layers "F.Cu" "F.Mask" "F.Paste")
			(net "HDD_PRSNT_3")
		)
		(pad "P6" smd rect
			(at -4.445 -1.82499 270)
			(size 0.6096 2.3622)
			(layers "F.Cu" "F.Mask" "F.Paste")
			(net "GND")
		)
		(pad "P7" smd rect
			(at -5.715 -1.82499 270)
			(size 0.6096 2.3622)
			(layers "F.Cu" "F.Mask" "F.Paste")
			(net "5V_PRE_3")
		)
		(pad "P8" smd rect
			(at -6.985 -1.82499 270)
			(size 0.6096 2.3622)
			(layers "F.Cu" "F.Mask" "F.Paste")
			(net "P5V_HDD3")
		)
		(pad "P9" smd rect
			(at -8.255 -1.82499 270)
			(size 0.6096 2.3622)
			(layers "F.Cu" "F.Mask" "F.Paste")
			(net "P5V_HDD3")
		)
		(pad "P10" smd rect
			(at -9.525 -1.82499 270)
			(size 0.6096 2.3622)
			(layers "F.Cu" "F.Mask" "F.Paste")
			(net "GND")
		)
		(pad "P11" smd rect
			(at -10.795 -1.82499 270)
			(size 0.6096 2.3622)
			(layers "F.Cu" "F.Mask" "F.Paste")
			(net "ACT_HDD_3")
		)
		(pad "P12" smd rect
			(at -12.065 -1.82499 270)
			(size 0.6096 2.3622)
			(layers "F.Cu" "F.Mask" "F.Paste")
			(net "GND")
		)
		(pad "P13" smd rect
			(at -13.335 -1.82499 270)
			(size 0.6096 2.3622)
			(layers "F.Cu" "F.Mask" "F.Paste")
			(net "12V_PRE_3")
		)
		(pad "P14" smd rect
			(at -14.605 -1.82499 270)
			(size 0.6096 2.3622)
			(layers "F.Cu" "F.Mask" "F.Paste")
			(net "P12V_HDD3")
		)
		(pad "P15" smd rect
			(at -15.875 -1.82499 270)
			(size 0.6096 2.3622)
			(layers "F.Cu" "F.Mask" "F.Paste")
			(net "P12V_HDD3")
		)
		(pad "S1" smd rect
			(at 15.875 -1.82499 270)
			(size 0.6096 2.3622)
			(layers "F.Cu" "F.Mask" "F.Paste")
			(net "GND")
		)
		(pad "S2" smd rect
			(at 14.605 -1.82499 270)
			(size 0.6096 2.3622)
			(layers "F.Cu" "F.Mask" "F.Paste")
			(net "SAS_HDD_RX_P3")
		)
		(pad "S3" smd rect
			(at 13.335 -1.82499 270)
			(size 0.6096 2.3622)
			(layers "F.Cu" "F.Mask" "F.Paste")
			(net "SAS_HDD_RX_N3")
		)
		(pad "S4" smd rect
			(at 12.065 -1.82499 270)
			(size 0.6096 2.3622)
			(layers "F.Cu" "F.Mask" "F.Paste")
			(net "GND")
		)
		(pad "S5" smd rect
			(at 10.795 -1.82499 270)
			(size 0.6096 2.3622)
			(layers "F.Cu" "F.Mask" "F.Paste")
			(net "PHY_DRV_A_TO_SCC_A_3_DN")
		)
		(pad "S6" smd rect
			(at 9.525 -1.82499 270)
			(size 0.6096 2.3622)
			(layers "F.Cu" "F.Mask" "F.Paste")
			(net "PHY_DRV_A_TO_SCC_A_3_DP")
		)
		(pad "S7" smd rect
			(at 8.255 -1.82499 270)
			(size 0.6096 2.3622)
			(layers "F.Cu" "F.Mask" "F.Paste")
			(net "GND")
		)
		(pad "S8" smd rect
			(at 7.480046 2.845054 270)
			(size 0.508 2.3622)
			(layers "F.Cu" "F.Mask" "F.Paste")
			(net "GND")
		)
		(pad "S9" smd rect
			(at 6.679946 2.845054 270)
			(size 0.508 2.3622)
			(layers "F.Cu" "F.Mask" "F.Paste")
			(net "Net_475")
		)
		(pad "S10" smd rect
			(at 5.8801 2.845054 270)
			(size 0.508 2.3622)
			(layers "F.Cu" "F.Mask" "F.Paste")
			(net "Net_367")
		)
		(pad "S11" smd rect
			(at 5.08 2.845054 270)
			(size 0.508 2.3622)
			(layers "F.Cu" "F.Mask" "F.Paste")
			(net "GND")
		)
		(pad "S12" smd rect
			(at 4.2799 2.845054 270)
			(size 0.508 2.3622)
			(layers "F.Cu" "F.Mask" "F.Paste")
			(net "Net_403")
		)
		(pad "S13" smd rect
			(at 3.480054 2.845054 270)
			(size 0.508 2.3622)
			(layers "F.Cu" "F.Mask" "F.Paste")
			(net "Net_439")
		)
		(pad "S14" smd rect
			(at 2.679954 2.845054 270)
			(size 0.508 2.3622)
			(layers "F.Cu" "F.Mask" "F.Paste")
			(net "GND")
		)
		(zone
			(layer "F.Cu")
			(hatch none 0.5)
			(connect_pads
				(clearance 0)
			)
			(min_thickness 0.25)
			(keepout
				(tracks not_allowed)
				(vias allowed)
				(pads allowed)
				(copperpour not_allowed)
				(footprints allowed)
			)
			(placement
				(enabled no)
				(sheetname "")
			)
			(fill
				(thermal_gap 0.5)
				(thermal_bridge_width 0.5)
				(island_removal_mode 0)
			)
			(polygon
				(pts
					(xy 126.507494 -304.648616) (xy 119.433594 -304.648616) (xy 119.433594 -311.582816) (xy 120.538494 -311.582816)
					(xy 120.538494 -307.468016) (xy 125.161294 -307.468016) (xy 125.161294 -311.582816) (xy 126.507494 -311.582816)
				)
			)
		)
		(zone
			(layer "F.Cu")
			(hatch none 0.5)
			(connect_pads
				(clearance 0)
			)
			(min_thickness 0.25)
			(keepout
				(tracks allowed)
				(vias not_allowed)
				(pads allowed)
				(copperpour not_allowed)
				(footprints allowed)
			)
			(placement
				(enabled no)
				(sheetname "")
			)
			(fill
				(thermal_gap 0.5)
				(thermal_bridge_width 0.5)
				(island_removal_mode 0)
			)
			(polygon
				(pts
					(xy 126.507494 -304.648616) (xy 119.433594 -304.648616) (xy 119.433594 -311.582816) (xy 120.538494 -311.582816)
					(xy 120.538494 -307.468016) (xy 125.161294 -307.468016) (xy 125.161294 -311.582816) (xy 126.507494 -311.582816)
				)
			)
		)
		(zone
			(layer "F.Cu")
			(hatch none 0.5)
			(connect_pads
				(clearance 0)
			)
			(min_thickness 0.25)
			(keepout
				(tracks not_allowed)
				(vias allowed)
				(pads allowed)
				(copperpour not_allowed)
				(footprints allowed)
			)
			(placement
				(enabled no)
				(sheetname "")
			)
			(fill
				(thermal_gap 0.5)
				(thermal_bridge_width 0.5)
				(island_removal_mode 0)
			)
			(polygon
				(pts
					(xy 126.507494 -271.171416) (xy 119.433594 -271.171416) (xy 119.433594 -264.237216) (xy 120.538494 -264.237216)
					(xy 120.538494 -268.352016) (xy 125.161294 -268.352016) (xy 125.161294 -264.237216) (xy 126.507494 -264.237216)
				)
			)
		)
		(zone
			(layer "F.Cu")
			(hatch none 0.5)
			(connect_pads
				(clearance 0)
			)
			(min_thickness 0.25)
			(keepout
				(tracks allowed)
				(vias not_allowed)
				(pads allowed)
				(copperpour not_allowed)
				(footprints allowed)
			)
			(placement
				(enabled no)
				(sheetname "")
			)
			(fill
				(thermal_gap 0.5)
				(thermal_bridge_width 0.5)
				(island_removal_mode 0)
			)
			(polygon
				(pts
					(xy 126.507494 -271.171416) (xy 119.433594 -271.171416) (xy 119.433594 -264.237216) (xy 120.538494 -264.237216)
					(xy 120.538494 -268.352016) (xy 125.161294 -268.352016) (xy 125.161294 -264.237216) (xy 126.507494 -264.237216)
				)
			)
		)
		(zone
			(layers "F.Cu" "B.Cu" "In1.Cu" "In2.Cu" "In3.Cu" "In4.Cu" "In5.Cu" "In6.Cu"
				"In7.Cu" "In8.Cu" "In9.Cu" "In10.Cu"
			)
			(hatch none 0.5)
			(connect_pads
				(clearance 0)
			)
			(min_thickness 0.25)
			(keepout
				(tracks not_allowed)
				(vias allowed)
				(pads allowed)
				(copperpour not_allowed)
				(footprints allowed)
			)
			(placement
				(enabled no)
				(sheetname "")
			)
			(fill
				(thermal_gap 0.5)
				(thermal_bridge_width 0.5)
				(island_removal_mode 0)
			)
			(polygon
				(pts
					(arc
						(start 123.624594 -269.035022)
						(mid 122.075194 -269.035022)
						(end 123.624594 -269.035022)
					)
				)
			)
		)
		(zone
			(layers "F.Cu" "B.Cu" "In1.Cu" "In2.Cu" "In3.Cu" "In4.Cu" "In5.Cu" "In6.Cu"
				"In7.Cu" "In8.Cu" "In9.Cu" "In10.Cu"
			)
			(hatch none 0.5)
			(connect_pads
				(clearance 0)
			)
			(min_thickness 0.25)
			(keepout
				(tracks not_allowed)
				(vias allowed)
				(pads allowed)
				(copperpour not_allowed)
				(footprints allowed)
			)
			(placement
				(enabled no)
				(sheetname "")
			)
			(fill
				(thermal_gap 0.5)
				(thermal_bridge_width 0.5)
				(island_removal_mode 0)
			)
			(polygon
				(pts
					(arc
						(start 123.827794 -306.78501)
						(mid 121.871994 -306.78501)
						(end 123.827794 -306.78501)
					)
				)
			)
		)
	)
	(footprint ""
		(layer "F.Cu")
		(at 436.401718 -294.424862 180)
		(property "Reference" "R324"
			(at 0 0 180)
			(layer "F.SilkS")
			(hide yes)
			(effects
				(font
					(size 1.27 1.27)
				)
			)
		)
		(property "Value" "91R3F-1-GP"
			(at -0.0254 -2.5146 180)
			(unlocked yes)
			(layer "F.Fab")
			(hide yes)
			(effects
				(font
					(size 1.016 1.016)
					(thickness 0.1524)
				)
			)
		)
		(property "Device Type" "R603H22"
			(at -0.0254 -4.0386 180)
			(unlocked yes)
			(layer "F.Fab")
			(hide yes)
			(effects
				(font
					(size 1.016 1.016)
					(thickness 0.1524)
				)
			)
		)
		(duplicate_pad_numbers_are_jumpers no)
		(fp_line
			(start 0.2032 0)
			(end 0.4826 0)
			(stroke
				(width 0.2032)
				(type default)
			)
			(layer "F.SilkS")
		)
		(fp_line
			(start -0.4826 0)
			(end -0.2032 0)
			(stroke
				(width 0.2032)
				(type default)
			)
			(layer "F.SilkS")
		)
		(fp_rect
			(start -0.5842 1.3335)
			(end 0.5842 -1.3335)
			(stroke
				(width 0)
				(type default)
			)
			(fill no)
			(layer "F.CrtYd")
		)
		(fp_rect
			(start -0.5842 1.3335)
			(end 0.5842 -1.3335)
			(stroke
				(width 0)
				(type default)
			)
			(fill no)
			(layer "F.Fab")
		)
		(pad "1" smd custom
			(at 0 -0.762 180)
			(size 0.2159 0.2159)
			(layers "F.Cu" "F.Mask" "F.Paste")
			(net "P5V_B")
			(options
				(clearance outline)
				(anchor circle)
			)
			(primitives
				(gr_poly
					(pts
						(arc
							(start -0.3302 -0.4318)
							(mid -0.402042 -0.402042)
							(end -0.4318 -0.3302)
						)
						(arc
							(start -0.4318 0.3302)
							(mid -0.402042 0.402042)
							(end -0.3302 0.4318)
						)
						(arc
							(start 0.3302 0.4318)
							(mid 0.402042 0.402042)
							(end 0.4318 0.3302)
						)
						(arc
							(start 0.4318 -0.3302)
							(mid 0.402042 -0.402042)
							(end 0.3302 -0.4318)
						)
					)
					(width 0)
					(fill yes)
				)
			)
		)
		(pad "2" smd custom
			(at 0 0.762 180)
			(size 0.2159 0.2159)
			(layers "F.Cu" "F.Mask" "F.Paste")
			(net "DRV_ACT_34")
			(options
				(clearance outline)
				(anchor circle)
			)
			(primitives
				(gr_poly
					(pts
						(arc
							(start -0.3302 -0.4318)
							(mid -0.402042 -0.402042)
							(end -0.4318 -0.3302)
						)
						(arc
							(start -0.4318 0.3302)
							(mid -0.402042 0.402042)
							(end -0.3302 0.4318)
						)
						(arc
							(start 0.3302 0.4318)
							(mid 0.402042 0.402042)
							(end 0.4318 0.3302)
						)
						(arc
							(start 0.4318 -0.3302)
							(mid 0.402042 -0.402042)
							(end 0.3302 -0.4318)
						)
					)
					(width 0)
					(fill yes)
				)
			)
		)
	)
	(footprint ""
		(layer "F.Cu")
		(at 458.9399 -164.596318 90)
		(property "Reference" "C334"
			(at 0 0 90)
			(layer "F.SilkS")
			(hide yes)
			(effects
				(font
					(size 1.27 1.27)
				)
			)
		)
		(property "Value" "SCD033U25V2KX-GP"
			(at 1.1811 -2.7051 90)
			(unlocked yes)
			(layer "F.Fab")
			(hide yes)
			(effects
				(font
					(size 1.016 1.016)
					(thickness 0.1524)
				)
			)
		)
		(property "Device Type" "C402H22"
			(at 1.1811 -4.2291 90)
			(unlocked yes)
			(layer "F.Fab")
			(hide yes)
			(effects
				(font
					(size 1.016 1.016)
					(thickness 0.1524)
				)
			)
		)
		(duplicate_pad_numbers_are_jumpers no)
		(fp_rect
			(start -0.4318 0.9525)
			(end 0.4318 -0.9525)
			(stroke
				(width 0)
				(type default)
			)
			(fill no)
			(layer "F.CrtYd")
		)
		(fp_rect
			(start -0.4318 0.9525)
			(end 0.4318 -0.9525)
			(stroke
				(width 0)
				(type default)
			)
			(fill no)
			(layer "F.Fab")
		)
		(pad "1" smd custom
			(at 0 -0.4445 90)
			(size 0.1524 0.1524)
			(layers "F.Cu" "F.Mask" "F.Paste")
			(net "SW_HDD_P22")
			(options
				(clearance outline)
				(anchor circle)
			)
			(primitives
				(gr_poly
					(pts
						(arc
							(start 0.3048 -0.2032)
							(mid 0.275042 -0.275042)
							(end 0.2032 -0.3048)
						)
						(arc
							(start -0.2032 -0.3048)
							(mid -0.275042 -0.275042)
							(end -0.3048 -0.2032)
						)
						(arc
							(start -0.3048 0.2032)
							(mid -0.275042 0.275042)
							(end -0.2032 0.3048)
						)
						(arc
							(start 0.2032 0.3048)
							(mid 0.275042 0.275042)
							(end 0.3048 0.2032)
						)
					)
					(width 0)
					(fill yes)
				)
			)
		)
		(pad "2" smd custom
			(at 0 0.4445 90)
			(size 0.1524 0.1524)
			(layers "F.Cu" "F.Mask" "F.Paste")
			(net "GND")
			(options
				(clearance outline)
				(anchor circle)
			)
			(primitives
				(gr_poly
					(pts
						(arc
							(start 0.3048 -0.2032)
							(mid 0.275042 -0.275042)
							(end 0.2032 -0.3048)
						)
						(arc
							(start -0.2032 -0.3048)
							(mid -0.275042 -0.275042)
							(end -0.3048 -0.2032)
						)
						(arc
							(start -0.3048 0.2032)
							(mid -0.275042 0.275042)
							(end -0.2032 0.3048)
						)
						(arc
							(start 0.2032 0.3048)
							(mid 0.275042 0.275042)
							(end 0.3048 0.2032)
						)
					)
					(width 0)
					(fill yes)
				)
			)
		)
	)
)
